FILE_TYPE = CONNECTIVITY;
{Allegro Design Entry HDL 16.6-p007 (v16-6-112F) 10/10/2012}
"PAGE_NUMBER" = 44;
0"NC";
1"M_A_DQS_DN<17:0>";
2"M_A_DQS_DP<17:0>";
3"M_A_DQ<63:0>";
4"M_A_MA<17:0>";
5"M_A_BA<1:0>";
6"M_A_BG<1:0>";
7"M_A_CLK_DP<3:0>";
8"M_A_CLK_DN<3:0>";
9"M_A_CS_N<7:0>";
10"M_A_CKE<3:0>";
11"M_A_ODT<3:0>";
12"M_A_ECC<7:0>";
13"GND\g";
14"PVTT_ABC\g";
15"PVPP_ABC\g";
16"GND\g";
17"GND\g";
18"P12V_NVDIMM_ABC\g";
19"GND\g";
20"PVPP_ABC\g";
21"PVDDQ_ABC\g";
22"M_A_MA<4>";
23"M_A_DQ<59>";
24"M_A_MA<16>";
25"M_A_DQS_DN<17>";
26"M_A_DQS_DN<15>";
27"M_A_DQS_DN<14>";
28"M_A_DQ<33>";
29"M_A_DQ<30>";
30"M_A_DQ<13>";
31"M_A_DQ<63>";
32"M_A_DQ<55>";
33"M_A_DQ<54>";
34"M_A_DQ<53>";
35"M_A_DQ<52>";
36"M_A_DQ<51>";
37"M_A_DQ<50>";
38"M_A_DQ<49>";
39"M_A_DQ<48>";
40"M_A_DQ<46>";
41"M_A_DQ<45>";
42"M_A_DQ<44>";
43"M_A_DQ<43>";
44"M_A_DQ<42>";
45"M_A_DQ<36>";
46"M_A_DQ<8>";
47"M_A_DQS_DN<0>";
48"M_A_DQS_DN<1>";
49"M_A_DQS_DN<2>";
50"M_A_DQS_DN<3>";
51"M_A_MA<13>";
52"M_A_DQ<57>";
53"M_A_MA<2>";
54"M_A_DQS_DN<8>";
55"M_A_VREF";
56"TP_CH_A_DIMM_A1_RFU_1";
57"TP_CH_A_DIMM_A1_RFU_2";
58"TP_CH_A_DIMM_A1_RFU_0";
59"SMB_DDR_ABC_VPP_SDA";
60"SMB_DDR_ABC_VPP_SCL";
61"M_A_ACT_N";
62"M_A_ALERT_N";
63"FM_ADR_COMPLETE_ABC_N";
64"FM_DIMM_EVENT_COD_N";
65"M_A_ECC<1>";
66"M_A_ECC<0>";
67"M_A_PAR";
68"M_ABC_RST_N";
69"M_A_CLK_DN<2>";
70"M_A_ECC<6>";
71"M_A_ECC<5>";
72"M_A_ECC<4>";
73"M_A_ECC<3>";
74"M_A_ECC<2>";
75"M_A_ECC<7>";
76"M_A_ODT<2>";
77"M_A_ODT<3>";
78"M_A_CKE<2>";
79"M_A_C<2>";
80"M_A_CLK_DP<2>";
81"M_A_CS_N<7>";
82"M_A_CS_N<6>";
83"M_A_CS_N<5>";
84"M_A_CKE<3>";
85"M_A_CS_N<4>";
86"M_A_CLK_DN<3>";
87"M_A_BA<1>";
88"M_A_MA<0>";
89"M_A_MA<1>";
90"M_A_CLK_DP<3>";
91"M_A_BG<0>";
92"M_A_BG<1>";
93"M_A_BA<0>";
94"M_A_MA<5>";
95"M_A_MA<6>";
96"M_A_MA<7>";
97"M_A_MA<8>";
98"M_A_MA<9>";
99"M_A_MA<10>";
100"M_A_MA<11>";
101"M_A_MA<3>";
102"M_A_MA<12>";
103"M_A_MA<17>";
104"M_A_MA<14>";
105"M_A_MA<15>";
106"M_A_DQ<29>";
107"M_A_DQ<28>";
108"M_A_DQ<62>";
109"M_A_DQ<61>";
110"M_A_DQ<60>";
111"M_A_DQ<56>";
112"M_A_DQ<41>";
113"M_A_DQ<40>";
114"M_A_DQ<39>";
115"M_A_DQ<34>";
116"M_A_DQ<32>";
117"M_A_DQ<31>";
118"M_A_DQ<25>";
119"M_A_DQ<22>";
120"M_A_DQ<21>";
121"M_A_DQ<16>";
122"M_A_DQ<12>";
123"M_A_DQ<10>";
124"M_A_DQ<7>";
125"M_A_DQ<1>";
126"M_A_DQ<0>";
127"M_A_DQ<35>";
128"M_A_DQ<38>";
129"M_A_DQ<27>";
130"M_A_DQ<26>";
131"M_A_DQ<15>";
132"M_A_DQ<17>";
133"M_A_DQ<58>";
134"M_A_DQ<47>";
135"M_A_DQ<2>";
136"M_A_DQ<3>";
137"M_A_DQ<4>";
138"M_A_DQ<5>";
139"M_A_DQ<37>";
140"M_A_DQ<24>";
141"M_A_DQ<23>";
142"M_A_DQ<14>";
143"M_A_DQ<18>";
144"M_A_DQ<11>";
145"M_A_DQ<20>";
146"M_A_DQ<19>";
147"M_A_DQ<9>";
148"M_A_DQ<6>";
149"M_A_DQS_DP<1>";
150"M_A_DQS_DP<0>";
151"M_A_DQS_DP<4>";
152"M_A_DQS_DP<3>";
153"M_A_DQS_DP<2>";
154"M_A_DQS_DN<4>";
155"M_A_DQS_DP<6>";
156"M_A_DQS_DP<5>";
157"M_A_DQS_DP<9>";
158"M_A_DQS_DP<8>";
159"M_A_DQS_DP<7>";
160"M_A_DQS_DN<9>";
161"M_A_DQS_DN<7>";
162"M_A_DQS_DN<6>";
163"M_A_DQS_DN<5>";
164"M_A_DQS_DP<12>";
165"M_A_DQS_DP<11>";
166"M_A_DQS_DP<10>";
167"M_A_DQS_DP<14>";
168"M_A_DQS_DP<13>";
169"M_A_DQS_DN<13>";
170"M_A_DQS_DN<12>";
171"M_A_DQS_DN<11>";
172"M_A_DQS_DN<10>";
173"M_A_DQS_DP<17>";
174"M_A_DQS_DP<16>";
175"M_A_DQS_DP<15>";
176"M_A_DQS_DN<16>";
%"GND"
"1","(-2650,750)","0","mstr_symbols","I1";
;
VOLTAGE"0"
BOM_COST"MEM"
CDS_LIB"mstr_symbols"
SIZE"1B"
BODY_TYPE"PLUMBING"
ROOM"DDR4_CH_A"
HDL_POWER"GND";
"A\NAC"13;
%"TAP"
"6","(100,3150)","2","mstr_standard","I100";
;
CDS_LIB"mstr_standard"
BODY_TYPE"PLUMBING"
HDL_TAP"TRUE";
"B \NAC \NWC"3;
"S \NAC"
BN"39"114;
%"TAP"
"6","(100,3200)","2","mstr_standard","I101";
;
CDS_LIB"mstr_standard"
BODY_TYPE"PLUMBING"
HDL_TAP"TRUE";
"B \NAC \NWC"3;
"S \NAC"
BN"40"113;
%"TAP"
"6","(100,3250)","2","mstr_standard","I102";
;
CDS_LIB"mstr_standard"
BODY_TYPE"PLUMBING"
HDL_TAP"TRUE";
"B \NAC \NWC"3;
"S \NAC"
BN"41"112;
%"TAP"
"6","(100,3300)","2","mstr_standard","I103";
;
CDS_LIB"mstr_standard"
BODY_TYPE"PLUMBING"
HDL_TAP"TRUE";
"B \NAC \NWC"3;
"S \NAC"
BN"42"44;
%"TAP"
"6","(100,3400)","2","mstr_standard","I104";
;
CDS_LIB"mstr_standard"
BODY_TYPE"PLUMBING"
HDL_TAP"TRUE";
"B \NAC \NWC"3;
"S \NAC"
BN"44"42;
%"TAP"
"6","(100,3350)","2","mstr_standard","I105";
;
CDS_LIB"mstr_standard"
BODY_TYPE"PLUMBING"
HDL_TAP"TRUE";
"B \NAC \NWC"3;
"S \NAC"
BN"43"43;
%"TAP"
"6","(100,3450)","2","mstr_standard","I106";
;
CDS_LIB"mstr_standard"
BODY_TYPE"PLUMBING"
HDL_TAP"TRUE";
"B \NAC \NWC"3;
"S \NAC"
BN"45"41;
%"TAP"
"6","(100,3500)","2","mstr_standard","I107";
;
CDS_LIB"mstr_standard"
BODY_TYPE"PLUMBING"
HDL_TAP"TRUE";
"B \NAC \NWC"3;
"S \NAC"
BN"46"40;
%"TAP"
"6","(100,3650)","2","mstr_standard","I108";
;
CDS_LIB"mstr_standard"
BODY_TYPE"PLUMBING"
HDL_TAP"TRUE";
"B \NAC \NWC"3;
"S \NAC"
BN"49"38;
%"TAP"
"6","(100,3600)","2","mstr_standard","I109";
;
CDS_LIB"mstr_standard"
BODY_TYPE"PLUMBING"
HDL_TAP"TRUE";
"B \NAC \NWC"3;
"S \NAC"
BN"48"39;
%"TAP"
"6","(100,3550)","2","mstr_standard","I110";
;
CDS_LIB"mstr_standard"
BODY_TYPE"PLUMBING"
HDL_TAP"TRUE";
"B \NAC \NWC"3;
"S \NAC"
BN"47"134;
%"TAP"
"6","(100,3700)","2","mstr_standard","I111";
;
CDS_LIB"mstr_standard"
BODY_TYPE"PLUMBING"
HDL_TAP"TRUE";
"B \NAC \NWC"3;
"S \NAC"
BN"50"37;
%"TAP"
"6","(100,3750)","2","mstr_standard","I112";
;
CDS_LIB"mstr_standard"
BODY_TYPE"PLUMBING"
HDL_TAP"TRUE";
"B \NAC \NWC"3;
"S \NAC"
BN"51"36;
%"TAP"
"6","(100,3850)","2","mstr_standard","I113";
;
CDS_LIB"mstr_standard"
BODY_TYPE"PLUMBING"
HDL_TAP"TRUE";
"B \NAC \NWC"3;
"S \NAC"
BN"53"34;
%"TAP"
"6","(100,3800)","2","mstr_standard","I114";
;
CDS_LIB"mstr_standard"
BODY_TYPE"PLUMBING"
HDL_TAP"TRUE";
"B \NAC \NWC"3;
"S \NAC"
BN"52"35;
%"TAP"
"6","(100,3900)","2","mstr_standard","I115";
;
CDS_LIB"mstr_standard"
BODY_TYPE"PLUMBING"
HDL_TAP"TRUE";
"B \NAC \NWC"3;
"S \NAC"
BN"54"33;
%"TAP"
"6","(100,3950)","2","mstr_standard","I116";
;
CDS_LIB"mstr_standard"
BODY_TYPE"PLUMBING"
HDL_TAP"TRUE";
"B \NAC \NWC"3;
"S \NAC"
BN"55"32;
%"TAP"
"6","(100,4000)","2","mstr_standard","I117";
;
CDS_LIB"mstr_standard"
BODY_TYPE"PLUMBING"
HDL_TAP"TRUE";
"B \NAC \NWC"3;
"S \NAC"
BN"56"111;
%"PVTT_ABC"
"1","(800,2350)","0","mstr_symbols","I118";
;
VOLTAGE"0.6V"
BOM_COST"MEM"
CDS_LIB"mstr_symbols"
BODY_TYPE"PLUMBING"
ROOM"DDR4_CH_A"
HDL_POWER"PVTT_ABC";
"G\NAC"14;
%"PVPP_ABC"
"1","(950,2650)","0","mstr_symbols","I119";
;
VOLTAGE"2.5V"
BOM_COST"MEM"
CDS_LIB"mstr_symbols"
BODY_TYPE"PLUMBING"
ROOM"DDR4_CH_A"
HDL_POWER"PVPP_ABC";
"G\NAC"15;
%"TAP"
"6","(-1450,1950)","0","mstr_standard","I12";
;
CDS_LIB"mstr_standard"
BODY_TYPE"PLUMBING"
HDL_TAP"TRUE";
"B \NAC \NWC"12;
"S \NAC"
BN"0"66;
%"SCONN288_H44441003"
"2","(1650,4000)","0","mstr_sconn","I120";
;
CDS_SEC"2"
LOCATION"J6T1"
PART_NUMBER"H44441-003"
MATERIAL"SCONN"
BOM_SS"NOPOP"
PACK_TYPE"PIP"
BOM_COST"MEM"
CDS_LIB"mstr_sconn"
SEC_TYPE"PIP"
SEC"2"
CDS_LOCATION"J6T1"
ROOM"DDR4_CH_A";
"DQS0N"
$PN"152"47;
"DQS0P"
$PN"153"150;
"DQS10N"
$PN"19"172;
"DQS10P"
$PN"18"166;
"DQS11N"
$PN"30"171;
"DQS11P"
$PN"29"165;
"DQS12N"
$PN"41"170;
"DQS12P"
$PN"40"164;
"DQS13N"
$PN"100"169;
"DQS13P"
$PN"99"168;
"DQS14N"
$PN"111"27;
"DQS14P"
$PN"110"167;
"DQS15N"
$PN"122"26;
"DQS15P"
$PN"121"175;
"DQS16N"
$PN"133"176;
"DQS16P"
$PN"132"174;
"DQS17N"
$PN"52"25;
"DQS17P"
$PN"51"173;
"DQS1N"
$PN"163"48;
"DQS1P"
$PN"164"149;
"DQS2N"
$PN"174"49;
"DQS2P"
$PN"175"153;
"DQS3N"
$PN"185"50;
"DQS3P"
$PN"186"152;
"DQS4N"
$PN"244"154;
"DQS4P"
$PN"245"151;
"DQS5N"
$PN"255"163;
"DQS5P"
$PN"256"156;
"DQS6N"
$PN"266"162;
"DQS6P"
$PN"267"155;
"DQS7N"
$PN"277"161;
"DQS7P"
$PN"278"159;
"DQS8N"
$PN"196"54;
"DQS8P"
$PN"197"158;
"DQS9N"
$PN"8"160;
"DQS9P"
$PN"7"157;
%"TAP"
"6","(-1450,4150)","0","mstr_standard","I122";
;
CDS_LIB"mstr_standard"
BODY_TYPE"PLUMBING"
HDL_TAP"TRUE";
"B \NAC \NWC"4;
"S \NAC"
BN"13"51;
%"TAP"
"6","(-1450,4050)","0","mstr_standard","I123";
;
CDS_LIB"mstr_standard"
BODY_TYPE"PLUMBING"
HDL_TAP"TRUE";
"B \NAC \NWC"4;
"S \NAC"
BN"11"100;
%"TAP"
"6","(-1450,4100)","0","mstr_standard","I124";
;
CDS_LIB"mstr_standard"
BODY_TYPE"PLUMBING"
HDL_TAP"TRUE";
"B \NAC \NWC"4;
"S \NAC"
BN"12"102;
%"TAP"
"6","(-1450,4200)","0","mstr_standard","I125";
;
CDS_LIB"mstr_standard"
BODY_TYPE"PLUMBING"
HDL_TAP"TRUE";
"B \NAC \NWC"4;
"S \NAC"
BN"14"104;
%"TAP"
"6","(-1450,4250)","0","mstr_standard","I126";
;
CDS_LIB"mstr_standard"
BODY_TYPE"PLUMBING"
HDL_TAP"TRUE";
"B \NAC \NWC"4;
"S \NAC"
BN"15"105;
%"TAP"
"6","(-1450,4300)","0","mstr_standard","I127";
;
CDS_LIB"mstr_standard"
BODY_TYPE"PLUMBING"
HDL_TAP"TRUE";
"B \NAC \NWC"4;
"S \NAC"
BN"16"24;
%"TAP"
"6","(-1450,4350)","0","mstr_standard","I128";
;
CDS_LIB"mstr_standard"
BODY_TYPE"PLUMBING"
HDL_TAP"TRUE";
"B \NAC \NWC"4;
"S \NAC"
BN"17"103;
%"TAP"
"6","(100,4050)","2","mstr_standard","I129";
;
CDS_LIB"mstr_standard"
BODY_TYPE"PLUMBING"
HDL_TAP"TRUE";
"B \NAC \NWC"3;
"S \NAC"
BN"57"52;
%"SCONN288_H44441003"
"1","(-700,2700)","0","mstr_sconn","I13";
;
CDS_SEC"1"
LOCATION"J6T1"
PART_NUMBER"H44441-003"
MATERIAL"SCONN"
BOM_SS"NOPOP"
PACK_TYPE"PIP"
BOM_COST"MEM"
CDS_LIB"mstr_sconn"
SEC_TYPE"PIP"
SEC"1"
CDS_LOCATION"J6T1"
ROOM"DDR4_CH_A";
"DQ<63>"
$PN"280"31;
"BA<1>"
$PN"224"87;
"CK1N"
$PN"219"86;
"CK0P"
$PN"74"80;
"S3_N_C<1>"
$PN"237"81;
"S2_N_C<0>"
$PN"93"82;
"S1_N"
$PN"89"83;
"DQ<29>"
$PN"181"106;
"DQ<28>"
$PN"36"107;
"C<2>"
$PN"235"79;
"A0"
$PN"79"88;
"A1"
$PN"72"89;
"A12"
$PN"65"102;
"A13"
$PN"232"51;
"A17"
$PN"234"103;
"A3"
$PN"71"101;
"A4"
$PN"214"22;
"A5"
$PN"213"94;
"A6"
$PN"69"95;
"A7"
$PN"211"96;
"A8"
$PN"68"97;
"A9"
$PN"66"98;
"CB<6>"
$PN"54"70;
"CB<5>"
$PN"192"71;
"CB<4>"
$PN"47"72;
"CB<3>"
$PN"201"73;
"CB<2>"
$PN"56"74;
"CB<1>"
$PN"194"65;
"CB<0>"
$PN"49"66;
"CK0N"
$PN"75"69;
"CKE<1>"
$PN"203"84;
"DQ<62>"
$PN"135"108;
"DQ<61>"
$PN"273"109;
"DQ<60>"
$PN"128"110;
"DQ<59>"
$PN"282"23;
"DQ<56>"
$PN"130"111;
"DQ<55>"
$PN"269"32;
"DQ<46>"
$PN"113"40;
"DQ<45>"
$PN"251"41;
"DQ<44>"
$PN"106"42;
"DQ<43>"
$PN"260"43;
"DQ<42>"
$PN"115"44;
"DQ<41>"
$PN"253"112;
"DQ<40>"
$PN"108"113;
"DQ<39>"
$PN"247"114;
"DQ<37>"
$PN"240"139;
"DQ<34>"
$PN"104"115;
"DQ<33>"
$PN"242"28;
"DQ<32>"
$PN"97"116;
"DQ<31>"
$PN"188"117;
"DQ<30>"
$PN"43"29;
"DQ<25>"
$PN"183"118;
"DQ<24>"
$PN"38"140;
"DQ<23>"
$PN"177"141;
"DQ<22>"
$PN"32"119;
"DQ<21>"
$PN"170"120;
"DQ<20>"
$PN"25"145;
"DQ<19>"
$PN"179"146;
"DQ<18>"
$PN"34"143;
"DQ<16>"
$PN"27"121;
"DQ<14>"
$PN"21"142;
"DQ<13>"
$PN"159"30;
"DQ<12>"
$PN"14"122;
"DQ<11>"
$PN"168"144;
"DQ<10>"
$PN"23"123;
"DQ<9>"
$PN"161"147;
"DQ<8>"
$PN"16"46;
"DQ<7>"
$PN"155"124;
"DQ<6>"
$PN"10"148;
"EVENT_N"
$PN"78"64;
"PAR"
$PN"222"67;
"RESET_N"
$PN"58"68;
"RFU<2>"
$PN"144"57;
"SCL"
$PN"141"60;
"SDA"
$PN"285"59;
"VREFCA"
$PN"146"55;
"CK1P"
$PN"218"90;
"BG<0>"
$PN"63"91;
"BG<1>"
$PN"207"92;
"BA<0>"
$PN"81"93;
"SA<0>"
$PN"139"20;
"VDDSPD"
$PN"284"20;
"SA<2>"
$PN"238"19;
"SA<1>"
$PN"140"19;
"DQ<1>"
$PN"150"125;
"DQ<0>"
$PN"5"126;
"ACT_N"
$PN"62"61;
"ALERT_N"
$PN"208"62;
"A2"
$PN"216"53;
"DQ<35>"
$PN"249"127;
"DQ<36>"
$PN"95"45;
"DQ<38>"
$PN"102"128;
"A10"
$PN"225"99;
"A11"
$PN"210"100;
"A14_WE_N"
$PN"228"104;
"A15_CAS_N"
$PN"86"105;
"A16_RAS_N"
$PN"82"24;
"CB<7>"
$PN"199"75;
"ODT<0>"
$PN"87"76;
"ODT<1>"
$PN"91"77;
"CKE<0>"
$PN"60"78;
"S0_N"
$PN"84"85;
"DQ<27>"
$PN"190"129;
"DQ<26>"
$PN"45"130;
"DQ<15>"
$PN"166"131;
"DQ<17>"
$PN"172"132;
"RFU<0>"
$PN"205"58;
"RFU<1>"
$PN"227"56;
"SAVE_N_NC"
$PN"230"63;
"DQ<57>"
$PN"275"52;
"DQ<58>"
$PN"137"133;
"DQ<54>"
$PN"124"33;
"DQ<53>"
$PN"262"34;
"DQ<52>"
$PN"117"35;
"DQ<51>"
$PN"271"36;
"DQ<50>"
$PN"126"37;
"DQ<49>"
$PN"264"38;
"DQ<48>"
$PN"119"39;
"DQ<47>"
$PN"258"134;
"DQ<2>"
$PN"12"135;
"DQ<3>"
$PN"157"136;
"DQ<4>"
$PN"3"137;
"DQ<5>"
$PN"148"138;
%"TAP"
"6","(100,4100)","2","mstr_standard","I130";
;
CDS_LIB"mstr_standard"
BODY_TYPE"PLUMBING"
HDL_TAP"TRUE";
"B \NAC \NWC"3;
"S \NAC"
BN"58"133;
%"TAP"
"6","(100,4150)","2","mstr_standard","I131";
;
CDS_LIB"mstr_standard"
BODY_TYPE"PLUMBING"
HDL_TAP"TRUE";
"B \NAC \NWC"3;
"S \NAC"
BN"59"23;
%"TAP"
"6","(100,4200)","2","mstr_standard","I132";
;
CDS_LIB"mstr_standard"
BODY_TYPE"PLUMBING"
HDL_TAP"TRUE";
"B \NAC \NWC"3;
"S \NAC"
BN"60"110;
%"TAP"
"6","(100,4300)","2","mstr_standard","I133";
;
CDS_LIB"mstr_standard"
BODY_TYPE"PLUMBING"
HDL_TAP"TRUE";
"B \NAC \NWC"3;
"S \NAC"
BN"62"108;
%"TAP"
"6","(100,4250)","2","mstr_standard","I134";
;
CDS_LIB"mstr_standard"
BODY_TYPE"PLUMBING"
HDL_TAP"TRUE";
"B \NAC \NWC"3;
"S \NAC"
BN"61"109;
%"TAP"
"6","(100,4350)","2","mstr_standard","I135";
;
CDS_LIB"mstr_standard"
BODY_TYPE"PLUMBING"
HDL_TAP"TRUE";
"B \NAC \NWC"3;
"S \NAC"
BN"63"31;
%"GND"
"1","(2750,1100)","2","mstr_symbols","I138";
;
VOLTAGE"0"
BOM_COST"MEM"
CDS_LIB"mstr_symbols"
SIZE"1B"
BODY_TYPE"PLUMBING"
ROOM"DDR4_CH_A"
HDL_POWER"GND";
"A\NAC"16;
%"SCONN288_H44441003"
"3","(3450,2400)","0","mstr_sconn","I139";
;
CDS_SEC"3"
LOCATION"J6T1"
PART_NUMBER"H44441-003"
MATERIAL"SCONN"
BOM_SS"NOPOP"
PACK_TYPE"PIP"
BOM_COST"MEM"
CDS_LIB"mstr_sconn"
SEC_TYPE"PIP"
SEC"3"
CDS_LOCATION"J6T1"
ROOM"DDR4_CH_A";
"VSS<46>"
$PN"147"17;
"VSS<45>"
$PN"149"17;
"VSS<87>"
$PN"15"16;
"VSS<86>"
$PN"17"16;
"VSS<85>"
$PN"20"16;
"VSS<84>"
$PN"22"16;
"VSS<83>"
$PN"24"16;
"VSS<82>"
$PN"26"16;
"VSS<81>"
$PN"28"16;
"VSS<80>"
$PN"31"16;
"VSS<79>"
$PN"33"16;
"VSS<78>"
$PN"35"16;
"VSS<77>"
$PN"37"16;
"VSS<76>"
$PN"39"16;
"VSS<75>"
$PN"42"16;
"VSS<74>"
$PN"44"16;
"VSS<73>"
$PN"46"16;
"VSS<72>"
$PN"48"16;
"VSS<71>"
$PN"50"16;
"VSS<70>"
$PN"53"16;
"VSS<69>"
$PN"55"16;
"VSS<68>"
$PN"57"16;
"VSS<67>"
$PN"94"16;
"VSS<66>"
$PN"96"16;
"VSS<65>"
$PN"98"16;
"VSS<64>"
$PN"101"16;
"VSS<63>"
$PN"103"16;
"VSS<62>"
$PN"105"16;
"VSS<61>"
$PN"107"16;
"VSS<60>"
$PN"109"16;
"VSS<59>"
$PN"112"16;
"VSS<58>"
$PN"114"16;
"VSS<57>"
$PN"116"16;
"VSS<56>"
$PN"118"16;
"VSS<55>"
$PN"120"16;
"VSS<54>"
$PN"123"16;
"VSS<53>"
$PN"125"16;
"VSS<52>"
$PN"127"16;
"VSS<51>"
$PN"129"16;
"VSS<50>"
$PN"131"16;
"VSS<49>"
$PN"134"16;
"VSS<48>"
$PN"136"16;
"VSS<47>"
$PN"138"16;
"VSS<44>"
$PN"151"17;
"VSS<43>"
$PN"154"17;
"VSS<42>"
$PN"156"17;
"VSS<41>"
$PN"158"17;
"VSS<40>"
$PN"160"17;
"VSS<39>"
$PN"162"17;
"VSS<38>"
$PN"165"17;
"VSS<37>"
$PN"167"17;
"VSS<36>"
$PN"169"17;
"VSS<35>"
$PN"171"17;
"VSS<34>"
$PN"173"17;
"VSS<33>"
$PN"176"17;
"VSS<32>"
$PN"178"17;
"VSS<31>"
$PN"180"17;
"VSS<30>"
$PN"182"17;
"VSS<29>"
$PN"184"17;
"VSS<28>"
$PN"187"17;
"VSS<27>"
$PN"189"17;
"VSS<26>"
$PN"191"17;
"VSS<25>"
$PN"193"17;
"VSS<24>"
$PN"195"17;
"VSS<23>"
$PN"198"17;
"VSS<22>"
$PN"200"17;
"VSS<21>"
$PN"202"17;
"VSS<20>"
$PN"239"17;
"VSS<19>"
$PN"241"17;
"VSS<18>"
$PN"243"17;
"VSS<17>"
$PN"246"17;
"VSS<16>"
$PN"248"17;
"VSS<15>"
$PN"250"17;
"VSS<14>"
$PN"252"17;
"VSS<13>"
$PN"254"17;
"VSS<12>"
$PN"257"17;
"VSS<11>"
$PN"259"17;
"VSS<10>"
$PN"261"17;
"VSS<9>"
$PN"263"17;
"VSS<8>"
$PN"265"17;
"VSS<7>"
$PN"268"17;
"VSS<6>"
$PN"270"17;
"VSS<5>"
$PN"272"17;
"VSS<4>"
$PN"274"17;
"VSS<3>"
$PN"276"17;
"VSS<2>"
$PN"279"17;
"VSS<1>"
$PN"281"17;
"VSS<0>"
$PN"283"17;
"VSS<88>"
$PN"13"16;
"VSS<89>"
$PN"11"16;
"VSS<90>"
$PN"9"16;
"VSS<91>"
$PN"6"16;
"VSS<92>"
$PN"4"16;
"VSS<93>"
$PN"2"16;
%"TAP"
"6","(2350,3150)","2","mstr_standard","I142";
;
CDS_LIB"mstr_standard"
BODY_TYPE"PLUMBING"
HDL_TAP"TRUE";
"B \NAC \NWC"2;
"S \NAC"
BN"0"150;
%"TAP"
"6","(2350,3250)","2","mstr_standard","I143";
;
CDS_LIB"mstr_standard"
BODY_TYPE"PLUMBING"
HDL_TAP"TRUE";
"B \NAC \NWC"2;
"S \NAC"
BN"1"149;
%"TAP"
"6","(2350,3450)","2","mstr_standard","I144";
;
CDS_LIB"mstr_standard"
BODY_TYPE"PLUMBING"
HDL_TAP"TRUE";
"B \NAC \NWC"2;
"S \NAC"
BN"3"152;
%"TAP"
"6","(2350,3350)","2","mstr_standard","I145";
;
CDS_LIB"mstr_standard"
BODY_TYPE"PLUMBING"
HDL_TAP"TRUE";
"B \NAC \NWC"2;
"S \NAC"
BN"2"153;
%"TAP"
"6","(2550,3100)","2","mstr_standard","I146";
;
CDS_LIB"mstr_standard"
BODY_TYPE"PLUMBING"
HDL_TAP"TRUE";
"B \NAC \NWC"1;
"S \NAC"
BN"0"47;
%"TAP"
"6","(2550,3200)","2","mstr_standard","I147";
;
CDS_LIB"mstr_standard"
BODY_TYPE"PLUMBING"
HDL_TAP"TRUE";
"B \NAC \NWC"1;
"S \NAC"
BN"1"48;
%"TAP"
"6","(2550,3300)","2","mstr_standard","I148";
;
CDS_LIB"mstr_standard"
BODY_TYPE"PLUMBING"
HDL_TAP"TRUE";
"B \NAC \NWC"1;
"S \NAC"
BN"2"49;
%"TAP"
"6","(2550,3400)","2","mstr_standard","I149";
;
CDS_LIB"mstr_standard"
BODY_TYPE"PLUMBING"
HDL_TAP"TRUE";
"B \NAC \NWC"1;
"S \NAC"
BN"3"50;
%"TAP"
"6","(2550,3500)","2","mstr_standard","I150";
;
CDS_LIB"mstr_standard"
BODY_TYPE"PLUMBING"
HDL_TAP"TRUE";
"B \NAC \NWC"1;
"S \NAC"
BN"4"154;
%"TAP"
"6","(2350,3650)","2","mstr_standard","I151";
;
CDS_LIB"mstr_standard"
BODY_TYPE"PLUMBING"
HDL_TAP"TRUE";
"B \NAC \NWC"2;
"S \NAC"
BN"5"156;
%"TAP"
"6","(2350,3750)","2","mstr_standard","I152";
;
CDS_LIB"mstr_standard"
BODY_TYPE"PLUMBING"
HDL_TAP"TRUE";
"B \NAC \NWC"2;
"S \NAC"
BN"6"155;
%"TAP"
"6","(2350,3550)","2","mstr_standard","I153";
;
CDS_LIB"mstr_standard"
BODY_TYPE"PLUMBING"
HDL_TAP"TRUE";
"B \NAC \NWC"2;
"S \NAC"
BN"4"151;
%"TAP"
"6","(2350,3950)","2","mstr_standard","I154";
;
CDS_LIB"mstr_standard"
BODY_TYPE"PLUMBING"
HDL_TAP"TRUE";
"B \NAC \NWC"2;
"S \NAC"
BN"8"158;
%"TAP"
"6","(2350,3850)","2","mstr_standard","I155";
;
CDS_LIB"mstr_standard"
BODY_TYPE"PLUMBING"
HDL_TAP"TRUE";
"B \NAC \NWC"2;
"S \NAC"
BN"7"159;
%"TAP"
"6","(2550,3600)","2","mstr_standard","I156";
;
CDS_LIB"mstr_standard"
BODY_TYPE"PLUMBING"
HDL_TAP"TRUE";
"B \NAC \NWC"1;
"S \NAC"
BN"5"163;
%"TAP"
"6","(2550,3700)","2","mstr_standard","I157";
;
CDS_LIB"mstr_standard"
BODY_TYPE"PLUMBING"
HDL_TAP"TRUE";
"B \NAC \NWC"1;
"S \NAC"
BN"6"162;
%"TAP"
"6","(2550,3800)","2","mstr_standard","I158";
;
CDS_LIB"mstr_standard"
BODY_TYPE"PLUMBING"
HDL_TAP"TRUE";
"B \NAC \NWC"1;
"S \NAC"
BN"7"161;
%"TAP"
"6","(2550,3900)","2","mstr_standard","I159";
;
CDS_LIB"mstr_standard"
BODY_TYPE"PLUMBING"
HDL_TAP"TRUE";
"B \NAC \NWC"1;
"S \NAC"
BN"8"54;
%"TAP"
"6","(2550,4000)","2","mstr_standard","I160";
;
CDS_LIB"mstr_standard"
BODY_TYPE"PLUMBING"
HDL_TAP"TRUE";
"B \NAC \NWC"1;
"S \NAC"
BN"9"160;
%"GND"
"1","(4150,1100)","2","mstr_symbols","I162";
;
VOLTAGE"0"
SIZE"1B"
BOM_COST"MEM"
CDS_LIB"mstr_symbols"
BODY_TYPE"PLUMBING"
ROOM"DDR4_CH_A"
HDL_POWER"GND";
"A\NAC"17;
%"TAP"
"6","(2350,4150)","2","mstr_standard","I163";
;
CDS_LIB"mstr_standard"
BODY_TYPE"PLUMBING"
HDL_TAP"TRUE";
"B \NAC \NWC"2;
"S \NAC"
BN"10"166;
%"TAP"
"6","(2350,4250)","2","mstr_standard","I164";
;
CDS_LIB"mstr_standard"
BODY_TYPE"PLUMBING"
HDL_TAP"TRUE";
"B \NAC \NWC"2;
"S \NAC"
BN"11"165;
%"TAP"
"6","(2350,4050)","2","mstr_standard","I165";
;
CDS_LIB"mstr_standard"
BODY_TYPE"PLUMBING"
HDL_TAP"TRUE";
"B \NAC \NWC"2;
"S \NAC"
BN"9"157;
%"TAP"
"6","(2350,4350)","2","mstr_standard","I166";
;
CDS_LIB"mstr_standard"
BODY_TYPE"PLUMBING"
HDL_TAP"TRUE";
"B \NAC \NWC"2;
"S \NAC"
BN"12"164;
%"TAP"
"6","(2350,4550)","2","mstr_standard","I167";
;
CDS_LIB"mstr_standard"
BODY_TYPE"PLUMBING"
HDL_TAP"TRUE";
"B \NAC \NWC"2;
"S \NAC"
BN"14"167;
%"TAP"
"6","(2350,4450)","2","mstr_standard","I168";
;
CDS_LIB"mstr_standard"
BODY_TYPE"PLUMBING"
HDL_TAP"TRUE";
"B \NAC \NWC"2;
"S \NAC"
BN"13"168;
%"TAP"
"6","(2550,4100)","2","mstr_standard","I169";
;
CDS_LIB"mstr_standard"
BODY_TYPE"PLUMBING"
HDL_TAP"TRUE";
"B \NAC \NWC"1;
"S \NAC"
BN"10"172;
%"TAP"
"6","(2550,4300)","2","mstr_standard","I170";
;
CDS_LIB"mstr_standard"
BODY_TYPE"PLUMBING"
HDL_TAP"TRUE";
"B \NAC \NWC"1;
"S \NAC"
BN"12"170;
%"TAP"
"6","(2550,4200)","2","mstr_standard","I171";
;
CDS_LIB"mstr_standard"
BODY_TYPE"PLUMBING"
HDL_TAP"TRUE";
"B \NAC \NWC"1;
"S \NAC"
BN"11"171;
%"TAP"
"6","(2550,4400)","2","mstr_standard","I172";
;
CDS_LIB"mstr_standard"
BODY_TYPE"PLUMBING"
HDL_TAP"TRUE";
"B \NAC \NWC"1;
"S \NAC"
BN"13"169;
%"TAP"
"6","(2550,4500)","2","mstr_standard","I173";
;
CDS_LIB"mstr_standard"
BODY_TYPE"PLUMBING"
HDL_TAP"TRUE";
"B \NAC \NWC"1;
"S \NAC"
BN"14"27;
%"TAP"
"6","(2350,4650)","2","mstr_standard","I174";
;
CDS_LIB"mstr_standard"
BODY_TYPE"PLUMBING"
HDL_TAP"TRUE";
"B \NAC \NWC"2;
"S \NAC"
BN"15"175;
%"TAP"
"6","(2350,4750)","2","mstr_standard","I175";
;
CDS_LIB"mstr_standard"
BODY_TYPE"PLUMBING"
HDL_TAP"TRUE";
"B \NAC \NWC"2;
"S \NAC"
BN"16"174;
%"TAP"
"6","(2350,4850)","2","mstr_standard","I176";
;
CDS_LIB"mstr_standard"
BODY_TYPE"PLUMBING"
HDL_TAP"TRUE";
"B \NAC \NWC"2;
"S \NAC"
BN"17"173;
%"TAP"
"6","(2550,4600)","2","mstr_standard","I177";
;
CDS_LIB"mstr_standard"
BODY_TYPE"PLUMBING"
HDL_TAP"TRUE";
"B \NAC \NWC"1;
"S \NAC"
BN"15"26;
%"TAP"
"6","(2550,4800)","2","mstr_standard","I178";
;
CDS_LIB"mstr_standard"
BODY_TYPE"PLUMBING"
HDL_TAP"TRUE";
"B \NAC \NWC"1;
"S \NAC"
BN"17"25;
%"TAP"
"6","(2550,4700)","2","mstr_standard","I179";
;
CDS_LIB"mstr_standard"
BODY_TYPE"PLUMBING"
HDL_TAP"TRUE";
"B \NAC \NWC"1;
"S \NAC"
BN"16"176;
%"P12V_NVDIMM_ABC"
"1","(2300,2725)","0","mstr_symbols","I184";
;
VOLTAGE"12.0"
CDS_LIB"mstr_symbols"
BODY_TYPE"PLUMBING"
HDL_POWER"P12V_NVDIMM_ABC";
"G\NAC"18;
%"CAP_A"
"1","(-2650,1000)","2","dev_discrete","I2";
;
LOCATION"C6T1"
PART_NUMBER"A36096-045"
VALUE"0.01UF"
TOLERANCE"10%"
PACK_TYPE"0402V"
VOLTAGE"25V"
MATERIAL"X7R"
CDS_LOCATION"C6T1"
BOM_COST"MEM"
CDS_LIB"dev_discrete"
CDS_SEC"1"
SEC_TYPE"0402V"
SEC"1"
ROOM"DDR4_CH_A";
"B"
$PN"2"13;
"A"
$PN"1"55;
%"TAP"
"6","(-1450,2100)","0","mstr_standard","I21";
;
CDS_LIB"mstr_standard"
BODY_TYPE"PLUMBING"
HDL_TAP"TRUE";
"B \NAC \NWC"12;
"S \NAC"
BN"3"73;
%"TAP"
"6","(-1450,2000)","0","mstr_standard","I22";
;
CDS_LIB"mstr_standard"
BODY_TYPE"PLUMBING"
HDL_TAP"TRUE";
"B \NAC \NWC"12;
"S \NAC"
BN"1"65;
%"TAP"
"6","(-1450,2050)","0","mstr_standard","I23";
;
CDS_LIB"mstr_standard"
BODY_TYPE"PLUMBING"
HDL_TAP"TRUE";
"B \NAC \NWC"12;
"S \NAC"
BN"2"74;
%"TAP"
"6","(-1450,2150)","0","mstr_standard","I24";
;
CDS_LIB"mstr_standard"
BODY_TYPE"PLUMBING"
HDL_TAP"TRUE";
"B \NAC \NWC"12;
"S \NAC"
BN"4"72;
%"TAP"
"6","(-1450,2200)","0","mstr_standard","I25";
;
CDS_LIB"mstr_standard"
BODY_TYPE"PLUMBING"
HDL_TAP"TRUE";
"B \NAC \NWC"12;
"S \NAC"
BN"5"71;
%"TAP"
"6","(-1450,2250)","0","mstr_standard","I26";
;
CDS_LIB"mstr_standard"
BODY_TYPE"PLUMBING"
HDL_TAP"TRUE";
"B \NAC \NWC"12;
"S \NAC"
BN"6"70;
%"TAP"
"6","(-1450,2400)","0","mstr_standard","I27";
;
CDS_LIB"mstr_standard"
BODY_TYPE"PLUMBING"
HDL_TAP"TRUE";
"B \NAC \NWC"11;
"S \NAC"
BN"2"76;
%"TAP"
"6","(-1450,2450)","0","mstr_standard","I28";
;
CDS_LIB"mstr_standard"
BODY_TYPE"PLUMBING"
HDL_TAP"TRUE";
"B \NAC \NWC"11;
"S \NAC"
BN"3"77;
%"TAP"
"6","(-1450,2300)","0","mstr_standard","I29";
;
CDS_LIB"mstr_standard"
BODY_TYPE"PLUMBING"
HDL_TAP"TRUE";
"B \NAC \NWC"12;
"S \NAC"
BN"7"75;
%"GND"
"1","(-3350,1350)","2","mstr_symbols","I3";
;
VOLTAGE"0"
SIZE"1B"
CDS_LIB"mstr_symbols"
BOM_COST"MEM"
BODY_TYPE"PLUMBING"
ROOM"DDR4_CH_A"
HDL_POWER"GND";
"A\NAC"19;
%"TAP"
"6","(-1650,3000)","0","mstr_standard","I30";
;
CDS_LIB"mstr_standard"
BODY_TYPE"PLUMBING"
HDL_TAP"TRUE";
"B \NAC \NWC"8;
"S \NAC"
BN"2"69;
%"TAP"
"6","(-1450,2600)","0","mstr_standard","I31";
;
CDS_LIB"mstr_standard"
BODY_TYPE"PLUMBING"
HDL_TAP"TRUE";
"B \NAC \NWC"10;
"S \NAC"
BN"3"84;
%"TAP"
"6","(-1450,2550)","0","mstr_standard","I32";
;
CDS_LIB"mstr_standard"
BODY_TYPE"PLUMBING"
HDL_TAP"TRUE";
"B \NAC \NWC"10;
"S \NAC"
BN"2"78;
%"TAP"
"6","(-1450,2700)","0","mstr_standard","I33";
;
CDS_LIB"mstr_standard"
BODY_TYPE"PLUMBING"
HDL_TAP"TRUE";
"B \NAC \NWC"9;
"S \NAC"
BN"4"85;
%"TAP"
"6","(-1450,2750)","0","mstr_standard","I34";
;
CDS_LIB"mstr_standard"
BODY_TYPE"PLUMBING"
HDL_TAP"TRUE";
"B \NAC \NWC"9;
"S \NAC"
BN"5"83;
%"TAP"
"6","(-1450,2850)","0","mstr_standard","I35";
;
CDS_LIB"mstr_standard"
BODY_TYPE"PLUMBING"
HDL_TAP"TRUE";
"B \NAC \NWC"9;
"S \NAC"
BN"7"81;
%"TAP"
"6","(-1450,2800)","0","mstr_standard","I36";
;
CDS_LIB"mstr_standard"
BODY_TYPE"PLUMBING"
HDL_TAP"TRUE";
"B \NAC \NWC"9;
"S \NAC"
BN"6"82;
%"TAP"
"6","(-1650,3100)","0","mstr_standard","I41";
;
CDS_LIB"mstr_standard"
BODY_TYPE"PLUMBING"
HDL_TAP"TRUE";
"B \NAC \NWC"8;
"S \NAC"
BN"3"86;
%"TAP"
"6","(-1450,3150)","0","mstr_standard","I42";
;
CDS_LIB"mstr_standard"
BODY_TYPE"PLUMBING"
HDL_TAP"TRUE";
"B \NAC \NWC"7;
"S \NAC"
BN"3"90;
%"TAP"
"6","(-1450,3050)","0","mstr_standard","I43";
;
CDS_LIB"mstr_standard"
BODY_TYPE"PLUMBING"
HDL_TAP"TRUE";
"B \NAC \NWC"7;
"S \NAC"
BN"2"80;
%"TAP"
"6","(-1450,3250)","0","mstr_standard","I44";
;
CDS_LIB"mstr_standard"
BODY_TYPE"PLUMBING"
HDL_TAP"TRUE";
"B \NAC \NWC"6;
"S \NAC"
BN"0"91;
%"TAP"
"6","(-1450,3300)","0","mstr_standard","I45";
;
CDS_LIB"mstr_standard"
BODY_TYPE"PLUMBING"
HDL_TAP"TRUE";
"B \NAC \NWC"6;
"S \NAC"
BN"1"92;
%"TAP"
"6","(-1450,3400)","0","mstr_standard","I46";
;
CDS_LIB"mstr_standard"
BODY_TYPE"PLUMBING"
HDL_TAP"TRUE";
"B \NAC \NWC"5;
"S \NAC"
BN"1"87;
%"TAP"
"6","(-1450,3350)","0","mstr_standard","I47";
;
CDS_LIB"mstr_standard"
BODY_TYPE"PLUMBING"
HDL_TAP"TRUE";
"B \NAC \NWC"5;
"S \NAC"
BN"0"93;
%"TAP"
"6","(-1450,3500)","0","mstr_standard","I48";
;
CDS_LIB"mstr_standard"
BODY_TYPE"PLUMBING"
HDL_TAP"TRUE";
"B \NAC \NWC"4;
"S \NAC"
BN"0"88;
%"TAP"
"6","(-1450,3700)","0","mstr_standard","I49";
;
CDS_LIB"mstr_standard"
BODY_TYPE"PLUMBING"
HDL_TAP"TRUE";
"B \NAC \NWC"4;
"S \NAC"
BN"4"22;
%"PVPP_ABC"
"1","(-3350,1700)","0","mstr_symbols","I5";
;
VOLTAGE"2.5V"
BOM_COST"MEM"
CDS_LIB"mstr_symbols"
BODY_TYPE"PLUMBING"
ROOM"DDR4_CH_A"
HDL_POWER"PVPP_ABC";
"G\NAC"20;
%"TAP"
"6","(-1450,3600)","0","mstr_standard","I50";
;
CDS_LIB"mstr_standard"
BODY_TYPE"PLUMBING"
HDL_TAP"TRUE";
"B \NAC \NWC"4;
"S \NAC"
BN"2"53;
%"TAP"
"6","(-1450,3550)","0","mstr_standard","I51";
;
CDS_LIB"mstr_standard"
BODY_TYPE"PLUMBING"
HDL_TAP"TRUE";
"B \NAC \NWC"4;
"S \NAC"
BN"1"89;
%"TAP"
"6","(-1450,3650)","0","mstr_standard","I52";
;
CDS_LIB"mstr_standard"
BODY_TYPE"PLUMBING"
HDL_TAP"TRUE";
"B \NAC \NWC"4;
"S \NAC"
BN"3"101;
%"TAP"
"6","(-1450,3750)","0","mstr_standard","I53";
;
CDS_LIB"mstr_standard"
BODY_TYPE"PLUMBING"
HDL_TAP"TRUE";
"B \NAC \NWC"4;
"S \NAC"
BN"5"94;
%"TAP"
"6","(-1450,3900)","0","mstr_standard","I54";
;
CDS_LIB"mstr_standard"
BODY_TYPE"PLUMBING"
HDL_TAP"TRUE";
"B \NAC \NWC"4;
"S \NAC"
BN"8"97;
%"TAP"
"6","(-1450,3800)","0","mstr_standard","I55";
;
CDS_LIB"mstr_standard"
BODY_TYPE"PLUMBING"
HDL_TAP"TRUE";
"B \NAC \NWC"4;
"S \NAC"
BN"6"95;
%"TAP"
"6","(-1450,3850)","0","mstr_standard","I56";
;
CDS_LIB"mstr_standard"
BODY_TYPE"PLUMBING"
HDL_TAP"TRUE";
"B \NAC \NWC"4;
"S \NAC"
BN"7"96;
%"TAP"
"6","(-1450,3950)","0","mstr_standard","I57";
;
CDS_LIB"mstr_standard"
BODY_TYPE"PLUMBING"
HDL_TAP"TRUE";
"B \NAC \NWC"4;
"S \NAC"
BN"9"98;
%"TAP"
"6","(-1450,4000)","0","mstr_standard","I58";
;
CDS_LIB"mstr_standard"
BODY_TYPE"PLUMBING"
HDL_TAP"TRUE";
"B \NAC \NWC"4;
"S \NAC"
BN"10"99;
%"TAP"
"6","(100,1200)","2","mstr_standard","I59";
;
CDS_LIB"mstr_standard"
BODY_TYPE"PLUMBING"
HDL_TAP"TRUE";
"B \NAC \NWC"3;
"S \NAC"
BN"0"126;
%"TAP"
"6","(100,1300)","2","mstr_standard","I60";
;
CDS_LIB"mstr_standard"
BODY_TYPE"PLUMBING"
HDL_TAP"TRUE";
"B \NAC \NWC"3;
"S \NAC"
BN"2"135;
%"TAP"
"6","(100,1250)","2","mstr_standard","I61";
;
CDS_LIB"mstr_standard"
BODY_TYPE"PLUMBING"
HDL_TAP"TRUE";
"B \NAC \NWC"3;
"S \NAC"
BN"1"125;
%"TAP"
"6","(100,1350)","2","mstr_standard","I62";
;
CDS_LIB"mstr_standard"
BODY_TYPE"PLUMBING"
HDL_TAP"TRUE";
"B \NAC \NWC"3;
"S \NAC"
BN"3"136;
%"TAP"
"6","(100,1450)","2","mstr_standard","I63";
;
CDS_LIB"mstr_standard"
BODY_TYPE"PLUMBING"
HDL_TAP"TRUE";
"B \NAC \NWC"3;
"S \NAC"
BN"5"138;
%"TAP"
"6","(100,1400)","2","mstr_standard","I64";
;
CDS_LIB"mstr_standard"
BODY_TYPE"PLUMBING"
HDL_TAP"TRUE";
"B \NAC \NWC"3;
"S \NAC"
BN"4"137;
%"TAP"
"6","(100,1600)","2","mstr_standard","I65";
;
CDS_LIB"mstr_standard"
BODY_TYPE"PLUMBING"
HDL_TAP"TRUE";
"B \NAC \NWC"3;
"S \NAC"
BN"8"46;
%"TAP"
"6","(100,1550)","2","mstr_standard","I66";
;
CDS_LIB"mstr_standard"
BODY_TYPE"PLUMBING"
HDL_TAP"TRUE";
"B \NAC \NWC"3;
"S \NAC"
BN"7"124;
%"TAP"
"6","(100,1500)","2","mstr_standard","I67";
;
CDS_LIB"mstr_standard"
BODY_TYPE"PLUMBING"
HDL_TAP"TRUE";
"B \NAC \NWC"3;
"S \NAC"
BN"6"148;
%"TAP"
"6","(100,1650)","2","mstr_standard","I68";
;
CDS_LIB"mstr_standard"
BODY_TYPE"PLUMBING"
HDL_TAP"TRUE";
"B \NAC \NWC"3;
"S \NAC"
BN"9"147;
%"TAP"
"6","(100,1700)","2","mstr_standard","I69";
;
CDS_LIB"mstr_standard"
BODY_TYPE"PLUMBING"
HDL_TAP"TRUE";
"B \NAC \NWC"3;
"S \NAC"
BN"10"123;
%"TAP"
"6","(100,1800)","2","mstr_standard","I70";
;
CDS_LIB"mstr_standard"
BODY_TYPE"PLUMBING"
HDL_TAP"TRUE";
"B \NAC \NWC"3;
"S \NAC"
BN"12"122;
%"TAP"
"6","(100,1750)","2","mstr_standard","I71";
;
CDS_LIB"mstr_standard"
BODY_TYPE"PLUMBING"
HDL_TAP"TRUE";
"B \NAC \NWC"3;
"S \NAC"
BN"11"144;
%"TAP"
"6","(100,1850)","2","mstr_standard","I72";
;
CDS_LIB"mstr_standard"
BODY_TYPE"PLUMBING"
HDL_TAP"TRUE";
"B \NAC \NWC"3;
"S \NAC"
BN"13"30;
%"TAP"
"6","(100,1950)","2","mstr_standard","I73";
;
CDS_LIB"mstr_standard"
BODY_TYPE"PLUMBING"
HDL_TAP"TRUE";
"B \NAC \NWC"3;
"S \NAC"
BN"15"131;
%"TAP"
"6","(100,1900)","2","mstr_standard","I74";
;
CDS_LIB"mstr_standard"
BODY_TYPE"PLUMBING"
HDL_TAP"TRUE";
"B \NAC \NWC"3;
"S \NAC"
BN"14"142;
%"SCONN288_H44441003"
"4","(1600,1650)","0","mstr_sconn","I75";
;
CDS_SEC"4"
LOCATION"J6T1"
MATERIAL"SCONN"
PART_NUMBER"H44441-003"
BOM_SS"NOPOP"
PACK_TYPE"PIP"
BOM_COST"MEM"
CDS_LIB"mstr_sconn"
SEC_TYPE"PIP"
SEC"4"
CDS_LOCATION"J6T1"
ROOM"DDR4_CH_A";
"VDD<0>"
$PN"236"21;
"VDD<6>"
$PN"220"21;
"VDD<10>"
$PN"209"21;
"VDD<13>"
$PN"92"21;
"VDD<16>"
$PN"85"21;
"VDD<19>"
$PN"76"21;
"VDD<23>"
$PN"64"21;
"VDD<25>"
$PN"59"21;
"VTT<0>"
$PN"221"14;
"12V<1>"
$PN"1"18;
"12V<0>"
$PN"145"18;
"VDD<24>"
$PN"61"21;
"VDD<22>"
$PN"67"21;
"VDD<21>"
$PN"70"21;
"VDD<20>"
$PN"73"21;
"VDD<18>"
$PN"80"21;
"VDD<17>"
$PN"83"21;
"VDD<15>"
$PN"88"21;
"VDD<14>"
$PN"90"21;
"VDD<12>"
$PN"204"21;
"VDD<11>"
$PN"206"21;
"VDD<9>"
$PN"212"21;
"VDD<8>"
$PN"215"21;
"VDD<7>"
$PN"217"21;
"VDD<5>"
$PN"223"21;
"VDD<4>"
$PN"226"21;
"VDD<3>"
$PN"229"21;
"VDD<2>"
$PN"231"21;
"VDD<1>"
$PN"233"21;
"VPP<4>"
$PN"142"15;
"VPP<3>"
$PN"143"15;
"VPP<2>"
$PN"288"15;
"VPP<1>"
$PN"286"15;
"VPP<0>"
$PN"287"15;
"VTT<1>"
$PN"77"14;
%"TAP"
"6","(100,2000)","2","mstr_standard","I76";
;
CDS_LIB"mstr_standard"
BODY_TYPE"PLUMBING"
HDL_TAP"TRUE";
"B \NAC \NWC"3;
"S \NAC"
BN"16"121;
%"TAP"
"6","(100,2050)","2","mstr_standard","I77";
;
CDS_LIB"mstr_standard"
BODY_TYPE"PLUMBING"
HDL_TAP"TRUE";
"B \NAC \NWC"3;
"S \NAC"
BN"17"132;
%"TAP"
"6","(100,2100)","2","mstr_standard","I78";
;
CDS_LIB"mstr_standard"
BODY_TYPE"PLUMBING"
HDL_TAP"TRUE";
"B \NAC \NWC"3;
"S \NAC"
BN"18"143;
%"TAP"
"6","(100,2150)","2","mstr_standard","I79";
;
CDS_LIB"mstr_standard"
BODY_TYPE"PLUMBING"
HDL_TAP"TRUE";
"B \NAC \NWC"3;
"S \NAC"
BN"19"146;
%"TAP"
"6","(100,2250)","2","mstr_standard","I80";
;
CDS_LIB"mstr_standard"
BODY_TYPE"PLUMBING"
HDL_TAP"TRUE";
"B \NAC \NWC"3;
"S \NAC"
BN"21"120;
%"TAP"
"6","(100,2200)","2","mstr_standard","I81";
;
CDS_LIB"mstr_standard"
BODY_TYPE"PLUMBING"
HDL_TAP"TRUE";
"B \NAC \NWC"3;
"S \NAC"
BN"20"145;
%"TAP"
"6","(100,2300)","2","mstr_standard","I82";
;
CDS_LIB"mstr_standard"
BODY_TYPE"PLUMBING"
HDL_TAP"TRUE";
"B \NAC \NWC"3;
"S \NAC"
BN"22"119;
%"TAP"
"6","(100,2350)","2","mstr_standard","I83";
;
CDS_LIB"mstr_standard"
BODY_TYPE"PLUMBING"
HDL_TAP"TRUE";
"B \NAC \NWC"3;
"S \NAC"
BN"23"141;
%"TAP"
"6","(100,2450)","2","mstr_standard","I84";
;
CDS_LIB"mstr_standard"
BODY_TYPE"PLUMBING"
HDL_TAP"TRUE";
"B \NAC \NWC"3;
"S \NAC"
BN"25"118;
%"TAP"
"6","(100,2500)","2","mstr_standard","I85";
;
CDS_LIB"mstr_standard"
BODY_TYPE"PLUMBING"
HDL_TAP"TRUE";
"B \NAC \NWC"3;
"S \NAC"
BN"26"130;
%"TAP"
"6","(100,2400)","2","mstr_standard","I86";
;
CDS_LIB"mstr_standard"
BODY_TYPE"PLUMBING"
HDL_TAP"TRUE";
"B \NAC \NWC"3;
"S \NAC"
BN"24"140;
%"TAP"
"6","(100,2550)","2","mstr_standard","I87";
;
CDS_LIB"mstr_standard"
BODY_TYPE"PLUMBING"
HDL_TAP"TRUE";
"B \NAC \NWC"3;
"S \NAC"
BN"27"129;
%"TAP"
"6","(100,2600)","2","mstr_standard","I88";
;
CDS_LIB"mstr_standard"
BODY_TYPE"PLUMBING"
HDL_TAP"TRUE";
"B \NAC \NWC"3;
"S \NAC"
BN"28"107;
%"TAP"
"6","(100,2700)","2","mstr_standard","I89";
;
CDS_LIB"mstr_standard"
BODY_TYPE"PLUMBING"
HDL_TAP"TRUE";
"B \NAC \NWC"3;
"S \NAC"
BN"30"29;
%"TAP"
"6","(100,2650)","2","mstr_standard","I90";
;
CDS_LIB"mstr_standard"
BODY_TYPE"PLUMBING"
HDL_TAP"TRUE";
"B \NAC \NWC"3;
"S \NAC"
BN"29"106;
%"TAP"
"6","(100,2750)","2","mstr_standard","I91";
;
CDS_LIB"mstr_standard"
BODY_TYPE"PLUMBING"
HDL_TAP"TRUE";
"B \NAC \NWC"3;
"S \NAC"
BN"31"117;
%"TAP"
"6","(100,2800)","2","mstr_standard","I92";
;
CDS_LIB"mstr_standard"
BODY_TYPE"PLUMBING"
HDL_TAP"TRUE";
"B \NAC \NWC"3;
"S \NAC"
BN"32"116;
%"TAP"
"6","(100,2850)","2","mstr_standard","I93";
;
CDS_LIB"mstr_standard"
BODY_TYPE"PLUMBING"
HDL_TAP"TRUE";
"B \NAC \NWC"3;
"S \NAC"
BN"33"28;
%"TAP"
"6","(100,2900)","2","mstr_standard","I94";
;
CDS_LIB"mstr_standard"
BODY_TYPE"PLUMBING"
HDL_TAP"TRUE";
"B \NAC \NWC"3;
"S \NAC"
BN"34"115;
%"TAP"
"6","(100,2950)","2","mstr_standard","I95";
;
CDS_LIB"mstr_standard"
BODY_TYPE"PLUMBING"
HDL_TAP"TRUE";
"B \NAC \NWC"3;
"S \NAC"
BN"35"127;
%"TAP"
"6","(100,3000)","2","mstr_standard","I96";
;
CDS_LIB"mstr_standard"
BODY_TYPE"PLUMBING"
HDL_TAP"TRUE";
"B \NAC \NWC"3;
"S \NAC"
BN"36"45;
%"PVDDQ_ABC"
"1","(600,2200)","0","mstr_symbols","I97";
;
VOLTAGE"1.2V"
BOM_COST"MEM"
CDS_LIB"mstr_symbols"
BODY_TYPE"PLUMBING"
ROOM"DDR4_CH_A"
HDL_POWER"PVDDQ_ABC";
"G\NAC"21;
%"TAP"
"6","(100,3050)","2","mstr_standard","I98";
;
CDS_LIB"mstr_standard"
BODY_TYPE"PLUMBING"
HDL_TAP"TRUE";
"B \NAC \NWC"3;
"S \NAC"
BN"37"139;
%"TAP"
"6","(100,3100)","2","mstr_standard","I99";
;
CDS_LIB"mstr_standard"
BODY_TYPE"PLUMBING"
HDL_TAP"TRUE";
"B \NAC \NWC"3;
"S \NAC"
BN"38"128;
END.
